# S9S_MB_2U (Grand Teton) — schematic netlist excerpt (pin names and nets, part order shuffled) for the footprints in the layout excerpt that follows; sources: Cadence DE-HDL packaged netlist, KiCad conversion of 03242023_DA0F0TMBIJ0_F0T_Motherboard_J_brd_V01_OCP.brd

C432  Q_CAP  22UF 4V 20% X6S  pkg C0402  page 77 : A = PVCCINFAON_CPU1 ; B = GND
PR559  Q_RES  100 1% CHIP  pkg 0402LF  page 296 : A = VSENSE_PVCCD_HV_CPU1_DP ; B = PVCCD_HV_CPU1
C824  Q_CAP_DIFFBUS  DIFF BUS_0.22UF 6.3V 20% X6S  pkg C0201  page 175 : \1\ = P5E_CPU1_PE1_TX_C_DN<6> ; \2\ = P5E_CPU1_PE1_TX_DN<6>

(kicad_pcb
	(version 20260206)
	(generator "pcbnew")
	(generator_version "10.0")
	(general
		(thickness 1.6)
		(legacy_teardrops no)
	)
	(paper "A4")
	(title_block
		(title "03242023_DA0F0TMBIJ0_F0T_Motherboard_J_brd_V01_OCP.brd")
		(comment 1 "Grand Teton / footprints 2952-2954 of 6105")
	)
	(layers
		(0 "F.Cu" signal "TOP")
		(4 "In1.Cu" signal "GND")
		(6 "In2.Cu" signal "IN1")
		(8 "In3.Cu" signal "GND1")
		(10 "In4.Cu" signal "IN2")
		(12 "In5.Cu" signal "GND2")
		(14 "In6.Cu" signal "IN3")
		(16 "In7.Cu" signal "GND3")
		(18 "In8.Cu" signal "VCC")
		(20 "In9.Cu" signal "VCC1")
		(22 "In10.Cu" signal "GND4")
		(24 "In11.Cu" signal "IN4")
		(26 "In12.Cu" signal "GND5")
		(28 "In13.Cu" signal "IN5")
		(30 "In14.Cu" signal "GND6")
		(32 "In15.Cu" signal "IN6")
		(34 "In16.Cu" signal "GND7")
		(2 "B.Cu" signal "BOTTOM")
		(9 "F.Adhes" user "F.Adhesive")
		(11 "B.Adhes" user "B.Adhesive")
		(13 "F.Paste" user "Package Geometry/Pastemask Top")
		(15 "B.Paste" user "Package Geometry/Pastemask Bottom")
		(5 "F.SilkS" user "Ref Des/Silkscreen Top")
		(7 "B.SilkS" user "Ref Des/Silkscreen Bottom")
		(1 "F.Mask" user "Board Geometry/Soldermask Top")
		(3 "B.Mask" user "Board Geometry/Soldermask Bottom")
		(17 "Dwgs.User" user "User.Drawings")
		(19 "Cmts.User" user "User.Comments")
		(21 "Eco1.User" user "User.Eco1")
		(23 "Eco2.User" user "User.Eco2")
		(25 "Edge.Cuts" user "Board Geometry/Outline")
		(27 "Margin" user)
		(31 "F.CrtYd" user "Package Geometry/Place Bound Top")
		(29 "B.CrtYd" user "Package Geometry/Place Bound Bottom")
		(35 "F.Fab" user "Ref Des/Assembly Top")
		(33 "B.Fab" user "Ref Des/Assembly Bottom")
	)
	(footprint ""
		(layer "F.Cu")
		(at 73.94448 -161.107882 180)
		(property "Reference" "PR559"
			(at 0 0 180)
			(layer "F.SilkS")
			(hide yes)
			(effects
				(font
					(size 1.27 1.27)
				)
			)
		)
		(property "Value" ""
			(at 0 0 180)
			(layer "F.Fab")
			(effects
				(font
					(size 1.27 1.27)
				)
			)
		)
		(duplicate_pad_numbers_are_jumpers no)
		(fp_line
			(start 0.7874 0.4064)
			(end -0.7874 0.4064)
			(stroke
				(width 0.1524)
				(type default)
			)
			(layer "F.SilkS")
		)
		(fp_line
			(start 0.7874 -0.4064)
			(end 0.7874 0.4064)
			(stroke
				(width 0.1524)
				(type default)
			)
			(layer "F.SilkS")
		)
		(fp_line
			(start -0.7874 0.4064)
			(end -0.7874 -0.4064)
			(stroke
				(width 0.1524)
				(type default)
			)
			(layer "F.SilkS")
		)
		(fp_line
			(start -0.7874 -0.4064)
			(end 0.7874 -0.4064)
			(stroke
				(width 0.1524)
				(type default)
			)
			(layer "F.SilkS")
		)
		(fp_line
			(start 0.67945 0.3048)
			(end 0.120396 0.3048)
			(stroke
				(width 0.1)
				(type default)
			)
			(layer "F.Fab")
		)
		(fp_line
			(start 0.67945 -0.3048)
			(end 0.67945 0.3048)
			(stroke
				(width 0.1)
				(type default)
			)
			(layer "F.Fab")
		)
		(fp_line
			(start 0.12065 -0.2794)
			(end 0.12065 -0.3048)
			(stroke
				(width 0.1)
				(type default)
			)
			(layer "F.Fab")
		)
		(fp_line
			(start 0.12065 -0.3048)
			(end 0.67945 -0.3048)
			(stroke
				(width 0.1)
				(type default)
			)
			(layer "F.Fab")
		)
		(fp_line
			(start 0.120396 0.3048)
			(end 0.120396 0.2794)
			(stroke
				(width 0.1)
				(type default)
			)
			(layer "F.Fab")
		)
		(fp_line
			(start 0.120396 0.2794)
			(end -0.12065 0.2794)
			(stroke
				(width 0.1)
				(type default)
			)
			(layer "F.Fab")
		)
		(fp_line
			(start -0.12065 0.3048)
			(end -0.67945 0.3048)
			(stroke
				(width 0.1)
				(type default)
			)
			(layer "F.Fab")
		)
		(fp_line
			(start -0.12065 0.2794)
			(end -0.12065 0.3048)
			(stroke
				(width 0.1)
				(type default)
			)
			(layer "F.Fab")
		)
		(fp_line
			(start -0.12065 -0.2794)
			(end 0.12065 -0.2794)
			(stroke
				(width 0.1)
				(type default)
			)
			(layer "F.Fab")
		)
		(fp_line
			(start -0.12065 -0.305054)
			(end -0.12065 -0.2794)
			(stroke
				(width 0.1)
				(type default)
			)
			(layer "F.Fab")
		)
		(fp_line
			(start -0.67945 0.3048)
			(end -0.67945 -0.305054)
			(stroke
				(width 0.1)
				(type default)
			)
			(layer "F.Fab")
		)
		(fp_line
			(start -0.67945 -0.305054)
			(end -0.12065 -0.305054)
			(stroke
				(width 0.1)
				(type default)
			)
			(layer "F.Fab")
		)
		(pad "1" smd circle
			(at -0.40005 0 180)
			(size 0 0)
			(layers "F.Cu" "F.Mask" "F.Paste")
			(net "VSENSE_PVCCD_HV_CPU1_DP")
		)
		(pad "2" smd circle
			(at 0.40005 0 180)
			(size 0 0)
			(layers "F.Cu" "F.Mask" "F.Paste")
			(net "PVCCD_HV_CPU1")
		)
	)
	(footprint ""
		(layer "F.Cu")
		(at 119.508016 -260.36524 -90)
		(property "Reference" "C432"
			(at 0 0 270)
			(layer "F.SilkS")
			(hide yes)
			(effects
				(font
					(size 1.27 1.27)
				)
			)
		)
		(property "Value" ""
			(at 0 0 270)
			(layer "F.Fab")
			(effects
				(font
					(size 1.27 1.27)
				)
			)
		)
		(duplicate_pad_numbers_are_jumpers no)
		(fp_line
			(start -0.7874 0.4064)
			(end -0.7874 -0.4064)
			(stroke
				(width 0.1524)
				(type default)
			)
			(layer "F.SilkS")
		)
		(fp_line
			(start 0.7874 0.4064)
			(end -0.7874 0.4064)
			(stroke
				(width 0.1524)
				(type default)
			)
			(layer "F.SilkS")
		)
		(fp_line
			(start -0.7874 -0.4064)
			(end 0.7874 -0.4064)
			(stroke
				(width 0.1524)
				(type default)
			)
			(layer "F.SilkS")
		)
		(fp_line
			(start 0.7874 -0.4064)
			(end 0.7874 0.4064)
			(stroke
				(width 0.1524)
				(type default)
			)
			(layer "F.SilkS")
		)
		(fp_line
			(start -0.67945 0.3048)
			(end -0.67945 -0.305054)
			(stroke
				(width 0.1)
				(type default)
			)
			(layer "F.Fab")
		)
		(fp_line
			(start -0.12065 0.3048)
			(end -0.67945 0.3048)
			(stroke
				(width 0.1)
				(type default)
			)
			(layer "F.Fab")
		)
		(fp_line
			(start 0.120396 0.3048)
			(end 0.120396 0.2794)
			(stroke
				(width 0.1)
				(type default)
			)
			(layer "F.Fab")
		)
		(fp_line
			(start 0.67945 0.3048)
			(end 0.120396 0.3048)
			(stroke
				(width 0.1)
				(type default)
			)
			(layer "F.Fab")
		)
		(fp_line
			(start -0.12065 0.2794)
			(end -0.12065 0.3048)
			(stroke
				(width 0.1)
				(type default)
			)
			(layer "F.Fab")
		)
		(fp_line
			(start 0.120396 0.2794)
			(end -0.12065 0.2794)
			(stroke
				(width 0.1)
				(type default)
			)
			(layer "F.Fab")
		)
		(fp_line
			(start -0.12065 -0.2794)
			(end 0.12065 -0.2794)
			(stroke
				(width 0.1)
				(type default)
			)
			(layer "F.Fab")
		)
		(fp_line
			(start 0.12065 -0.2794)
			(end 0.12065 -0.3048)
			(stroke
				(width 0.1)
				(type default)
			)
			(layer "F.Fab")
		)
		(fp_line
			(start 0.12065 -0.3048)
			(end 0.67945 -0.3048)
			(stroke
				(width 0.1)
				(type default)
			)
			(layer "F.Fab")
		)
		(fp_line
			(start 0.67945 -0.3048)
			(end 0.67945 0.3048)
			(stroke
				(width 0.1)
				(type default)
			)
			(layer "F.Fab")
		)
		(fp_line
			(start -0.67945 -0.305054)
			(end -0.12065 -0.305054)
			(stroke
				(width 0.1)
				(type default)
			)
			(layer "F.Fab")
		)
		(fp_line
			(start -0.12065 -0.305054)
			(end -0.12065 -0.2794)
			(stroke
				(width 0.1)
				(type default)
			)
			(layer "F.Fab")
		)
		(pad "1" smd circle
			(at -0.40005 0 270)
			(size 0 0)
			(layers "F.Cu" "F.Mask" "F.Paste")
			(net "PVCCINFAON_CPU1")
		)
		(pad "2" smd circle
			(at 0.40005 0 270)
			(size 0 0)
			(layers "F.Cu" "F.Mask" "F.Paste")
			(net "GND")
		)
	)
	(footprint ""
		(layer "F.Cu")
		(at 40.960294 -17.623536 90)
		(property "Reference" "C824"
			(at 0 0 90)
			(layer "F.SilkS")
			(hide yes)
			(effects
				(font
					(size 1.27 1.27)
				)
			)
		)
		(property "Value" ""
			(at 0 0 90)
			(layer "F.Fab")
			(effects
				(font
					(size 1.27 1.27)
				)
			)
		)
		(duplicate_pad_numbers_are_jumpers no)
		(fp_line
			(start 0.299974 -0.150114)
			(end 0.299974 0.150114)
			(stroke
				(width 0.1)
				(type default)
			)
			(layer "F.Fab")
		)
		(fp_line
			(start -0.299974 -0.150114)
			(end 0.299974 -0.150114)
			(stroke
				(width 0.1)
				(type default)
			)
			(layer "F.Fab")
		)
		(fp_line
			(start 0.299974 0.150114)
			(end -0.299974 0.150114)
			(stroke
				(width 0.1)
				(type default)
			)
			(layer "F.Fab")
		)
		(fp_line
			(start -0.299974 0.150114)
			(end -0.299974 -0.150114)
			(stroke
				(width 0.1)
				(type default)
			)
			(layer "F.Fab")
		)
		(pad "1" smd rect
			(at -0.2667 0 90)
			(size 0.3048 0.381)
			(layers "F.Cu" "F.Mask" "F.Paste")
			(net "P5E_CPU1_PE1_TX_C_DN<6>")
		)
		(pad "2" smd rect
			(at 0.2667 0 90)
			(size 0.3048 0.381)
			(layers "F.Cu" "F.Mask" "F.Paste")
			(net "P5E_CPU1_PE1_TX_DN<6>")
		)
	)
)
